(kicad_pcb
	(version 20260206)
	(generator "pcbnew")
	(generator_version "10.0")
	(general
		(thickness 1.6)
		(legacy_teardrops no)
	)
	(paper "A4")
	(title_block
		(title "03242023_DA0F0TMBIJ0_F0T_Motherboard_J_brd_V01_OCP.brd")
		(comment 1 "Grand Teton / footprint 3077 of 6105 (J41), pads 108-175 of 175")
	)
	(layers
		(0 "F.Cu" signal "TOP")
		(4 "In1.Cu" signal "GND")
		(6 "In2.Cu" signal "IN1")
		(8 "In3.Cu" signal "GND1")
		(10 "In4.Cu" signal "IN2")
		(12 "In5.Cu" signal "GND2")
		(14 "In6.Cu" signal "IN3")
		(16 "In7.Cu" signal "GND3")
		(18 "In8.Cu" signal "VCC")
		(20 "In9.Cu" signal "VCC1")
		(22 "In10.Cu" signal "GND4")
		(24 "In11.Cu" signal "IN4")
		(26 "In12.Cu" signal "GND5")
		(28 "In13.Cu" signal "IN5")
		(30 "In14.Cu" signal "GND6")
		(32 "In15.Cu" signal "IN6")
		(34 "In16.Cu" signal "GND7")
		(2 "B.Cu" signal "BOTTOM")
		(9 "F.Adhes" user "F.Adhesive")
		(11 "B.Adhes" user "B.Adhesive")
		(13 "F.Paste" user "Package Geometry/Pastemask Top")
		(15 "B.Paste" user "Package Geometry/Pastemask Bottom")
		(5 "F.SilkS" user "Ref Des/Silkscreen Top")
		(7 "B.SilkS" user "Ref Des/Silkscreen Bottom")
		(1 "F.Mask" user "Board Geometry/Soldermask Top")
		(3 "B.Mask" user "Board Geometry/Soldermask Bottom")
		(17 "Dwgs.User" user "User.Drawings")
		(19 "Cmts.User" user "User.Comments")
		(21 "Eco1.User" user "User.Eco1")
		(23 "Eco2.User" user "User.Eco2")
		(25 "Edge.Cuts" user "Board Geometry/Outline")
		(27 "Margin" user)
		(31 "F.CrtYd" user "Package Geometry/Place Bound Top")
		(29 "B.CrtYd" user "Package Geometry/Place Bound Bottom")
		(35 "F.Fab" user "Ref Des/Assembly Top")
		(33 "B.Fab" user "Ref Des/Assembly Bottom")
	)
	(footprint ""
		(layer "F.Cu")
		(at 160.402016 -10.850118 -90)
		(property "Reference" "J41"
			(at -12.075414 24.511762 0)
			(unlocked yes)
			(layer "F.SilkS")
			(effects
				(font
					(size 0.7874 0.5842)
					(thickness 0.1524)
				)
				(justify left)
			)
		)
		(property "Value" ""
			(at 0 0 270)
			(layer "F.Fab")
			(effects
				(font
					(size 1.27 1.27)
				)
			)
		)
		(duplicate_pad_numbers_are_jumpers no)
		(pad "B36" smd rect
			(at -5.700014 5.945124 180)
			(size 0.381 1.4478)
			(layers "F.Cu" "F.Mask" "F.Paste")
			(net "SGPIO_DI_1")
		)
		(pad "B37" smd rect
			(at -5.700014 6.545072 180)
			(size 0.381 1.4478)
			(layers "F.Cu" "F.Mask" "F.Paste")
			(net "SGPIO_LD_1")
		)
		(pad "B38" smd rect
			(at -5.700014 7.14502 180)
			(size 0.381 1.4478)
			(layers "F.Cu" "F.Mask" "F.Paste")
			(net "GND")
		)
		(pad "B39" smd rect
			(at -5.700014 7.744968 180)
			(size 0.381 1.4478)
			(layers "F.Cu" "F.Mask" "F.Paste")
			(net "RST_SGPIO_RESET_N")
		)
		(pad "B40" smd rect
			(at -5.700014 8.344916 180)
			(size 0.381 1.4478)
			(layers "F.Cu" "F.Mask" "F.Paste")
			(net "IRQ_SGPIO_INTR_N")
		)
		(pad "B41" smd rect
			(at -5.700014 8.945118 180)
			(size 0.381 1.4478)
			(layers "F.Cu" "F.Mask" "F.Paste")
			(net "P3V_BAT_R1")
		)
		(pad "B42" smd rect
			(at -5.700014 9.545066 180)
			(size 0.381 1.4478)
			(layers "F.Cu" "F.Mask" "F.Paste")
			(net "FM_AC_PWR_BTN_N")
		)
		(pad "B43" smd rect
			(at -5.700014 14.454886 180)
			(size 0.381 1.4478)
			(layers "F.Cu" "F.Mask" "F.Paste")
			(net "TP_SPI_2_PLD_CLK")
		)
		(pad "B44" smd rect
			(at -5.700014 15.055088 180)
			(size 0.381 1.4478)
			(layers "F.Cu" "F.Mask" "F.Paste")
			(net "TP_SPI_2_PLD_CS_N")
		)
		(pad "B45" smd rect
			(at -5.700014 15.655036 180)
			(size 0.381 1.4478)
			(layers "F.Cu" "F.Mask" "F.Paste")
			(net "TP_SPI_2_PLD_IO0")
		)
		(pad "B46" smd rect
			(at -5.700014 16.254984 180)
			(size 0.381 1.4478)
			(layers "F.Cu" "F.Mask" "F.Paste")
			(net "TP_SPI_2_PLD_IO1")
		)
		(pad "B47" smd rect
			(at -5.700014 16.854932 180)
			(size 0.381 1.4478)
			(layers "F.Cu" "F.Mask" "F.Paste")
			(net "TP_SPI_2_PLD_IO2")
		)
		(pad "B48" smd rect
			(at -5.700014 17.45488 180)
			(size 0.381 1.4478)
			(layers "F.Cu" "F.Mask" "F.Paste")
			(net "TP_SPI_2_PLD_IO3")
		)
		(pad "B49" smd rect
			(at -5.700014 18.055082 180)
			(size 0.381 1.4478)
			(layers "F.Cu" "F.Mask" "F.Paste")
			(net "GND")
		)
		(pad "B50" smd rect
			(at -5.700014 18.65503 180)
			(size 0.381 1.4478)
			(layers "F.Cu" "F.Mask" "F.Paste")
			(net "USB2_HOST_BMC_B_DP")
		)
		(pad "B51" smd rect
			(at -5.700014 19.254978 180)
			(size 0.381 1.4478)
			(layers "F.Cu" "F.Mask" "F.Paste")
			(net "USB2_HOST_BMC_B_DN")
		)
		(pad "B52" smd rect
			(at -5.700014 19.854926 180)
			(size 0.381 1.4478)
			(layers "F.Cu" "F.Mask" "F.Paste")
			(net "GND")
		)
		(pad "B53" smd rect
			(at -5.700014 20.455128 180)
			(size 0.381 1.4478)
			(layers "F.Cu" "F.Mask" "F.Paste")
			(net "USB2_8_DP")
		)
		(pad "B54" smd rect
			(at -5.700014 21.055076 180)
			(size 0.381 1.4478)
			(layers "F.Cu" "F.Mask" "F.Paste")
			(net "USB2_8_DN")
		)
		(pad "B55" smd rect
			(at -5.700014 21.655024 180)
			(size 0.381 1.4478)
			(layers "F.Cu" "F.Mask" "F.Paste")
			(net "GND")
		)
		(pad "B56" smd rect
			(at -5.700014 22.254972 180)
			(size 0.381 1.4478)
			(layers "F.Cu" "F.Mask" "F.Paste")
			(net "USB2_HUB_2_BUF_EXT_DP")
		)
		(pad "B57" smd rect
			(at -5.700014 22.85492 180)
			(size 0.381 1.4478)
			(layers "F.Cu" "F.Mask" "F.Paste")
			(net "USB2_HUB_2_BUF_EXT_DN")
		)
		(pad "B58" smd rect
			(at -5.700014 23.455122 180)
			(size 0.381 1.4478)
			(layers "F.Cu" "F.Mask" "F.Paste")
			(net "GND")
		)
		(pad "B59" smd rect
			(at -5.700014 24.05507 180)
			(size 0.381 1.4478)
			(layers "F.Cu" "F.Mask" "F.Paste")
			(net "USB3_PCH_TX_BUF_C_DP<4>")
		)
		(pad "B60" smd rect
			(at -5.700014 24.655018 180)
			(size 0.381 1.4478)
			(layers "F.Cu" "F.Mask" "F.Paste")
			(net "USB3_PCH_TX_BUF_C_DN<4>")
		)
		(pad "B61" smd rect
			(at -5.700014 25.254966 180)
			(size 0.381 1.4478)
			(layers "F.Cu" "F.Mask" "F.Paste")
			(net "GND")
		)
		(pad "B62" smd rect
			(at -5.700014 25.854914 180)
			(size 0.381 1.4478)
			(layers "F.Cu" "F.Mask" "F.Paste")
			(net "TP_PCIE_HPM_TXP<1>")
		)
		(pad "B63" smd rect
			(at -5.700014 26.455116 180)
			(size 0.381 1.4478)
			(layers "F.Cu" "F.Mask" "F.Paste")
			(net "TP_PCIE_HPM_TXN<1>")
		)
		(pad "B64" smd rect
			(at -5.700014 27.055064 180)
			(size 0.381 1.4478)
			(layers "F.Cu" "F.Mask" "F.Paste")
			(net "GND")
		)
		(pad "B65" smd rect
			(at -5.700014 27.655012 180)
			(size 0.381 1.4478)
			(layers "F.Cu" "F.Mask" "F.Paste")
			(net "P2E_MB_BMC_TX_C_DP<0>")
		)
		(pad "B66" smd rect
			(at -5.700014 28.25496 180)
			(size 0.381 1.4478)
			(layers "F.Cu" "F.Mask" "F.Paste")
			(net "P2E_MB_BMC_TX_C_DN<0>")
		)
		(pad "B67" smd rect
			(at -5.700014 28.854908 180)
			(size 0.381 1.4478)
			(layers "F.Cu" "F.Mask" "F.Paste")
			(net "GND")
		)
		(pad "B68" smd rect
			(at -5.700014 29.45511 180)
			(size 0.381 1.4478)
			(layers "F.Cu" "F.Mask" "F.Paste")
			(net "TP_PCIE_HPM_TXP<3>")
		)
		(pad "B69" smd rect
			(at -5.700014 30.055058 180)
			(size 0.381 1.4478)
			(layers "F.Cu" "F.Mask" "F.Paste")
			(net "TP_PCIE_HPM_TXN<3>")
		)
		(pad "B70" smd rect
			(at -5.700014 30.655006 180)
			(size 0.381 1.4478)
			(layers "F.Cu" "F.Mask" "F.Paste")
			(net "GND")
		)
		(pad "G1" thru_hole circle
			(at 2.400046 -32.759904 180)
			(size 1.6256 1.6256)
			(drill 1.1176)
			(layers "*.Cu" "*.Mask")
			(remove_unused_layers no)
			(net "GND")
			(clearance 0)
		)
		(pad "G2" thru_hole circle
			(at 2.400046 -20.379944 180)
			(size 1.6256 1.6256)
			(drill 1.1176)
			(layers "*.Cu" "*.Mask")
			(remove_unused_layers no)
			(net "GND")
			(clearance 0)
		)
		(pad "G3" thru_hole circle
			(at 2.400046 0 180)
			(size 1.6256 1.6256)
			(drill 1.1176)
			(layers "*.Cu" "*.Mask")
			(remove_unused_layers no)
			(net "GND")
			(clearance 0)
		)
		(pad "G4" thru_hole circle
			(at 2.400046 12.5349 180)
			(size 1.6256 1.6256)
			(drill 1.1176)
			(layers "*.Cu" "*.Mask")
			(remove_unused_layers no)
			(net "GND")
			(clearance 0)
		)
		(pad "G5" thru_hole circle
			(at 2.400046 32.759904 180)
			(size 1.6256 1.6256)
			(drill 1.1176)
			(layers "*.Cu" "*.Mask")
			(remove_unused_layers no)
			(net "GND")
			(clearance 0)
		)
		(pad "OA1" smd rect
			(at -2.750058 -30.660086 180)
			(size 0.381 1.4478)
			(layers "F.Cu" "F.Mask" "F.Paste")
			(net "P12V_SCM")
		)
		(pad "OA2" smd rect
			(at -2.750058 -30.059884 180)
			(size 0.381 1.4478)
			(layers "F.Cu" "F.Mask" "F.Paste")
			(net "P12V_SCM")
		)
		(pad "OA3" smd rect
			(at -2.750058 -29.459936 180)
			(size 0.381 1.4478)
			(layers "F.Cu" "F.Mask" "F.Paste")
			(net "GND")
		)
		(pad "OA4" smd rect
			(at -2.750058 -28.859988 180)
			(size 0.381 1.4478)
			(layers "F.Cu" "F.Mask" "F.Paste")
			(net "GND")
		)
		(pad "OA5" smd rect
			(at -2.750058 -28.26004 180)
			(size 0.381 1.4478)
			(layers "F.Cu" "F.Mask" "F.Paste")
			(net "I3C_SPD_DDRABCD_CPU0_BMC_R_SCL")
		)
		(pad "OA6" smd rect
			(at -2.750058 -27.660092 180)
			(size 0.381 1.4478)
			(layers "F.Cu" "F.Mask" "F.Paste")
			(net "I3C_SPD_DDRABCD_CPU0_BMC_R_SDA")
		)
		(pad "OA7" smd rect
			(at -2.750058 -27.05989 180)
			(size 0.381 1.4478)
			(layers "F.Cu" "F.Mask" "F.Paste")
			(net "I3C_SPD_DDREFGH_CPU0_BMC_R_SCL")
		)
		(pad "OA8" smd rect
			(at -2.750058 -26.459942 180)
			(size 0.381 1.4478)
			(layers "F.Cu" "F.Mask" "F.Paste")
			(net "I3C_SPD_DDREFGH_CPU0_BMC_R_SDA")
		)
		(pad "OA9" smd rect
			(at -2.750058 -25.859994 180)
			(size 0.381 1.4478)
			(layers "F.Cu" "F.Mask" "F.Paste")
			(net "I3C_SPD_DDRABCD_CPU1_BMC_R_SCL")
		)
		(pad "OA10" smd rect
			(at -2.750058 -25.260046 180)
			(size 0.381 1.4478)
			(layers "F.Cu" "F.Mask" "F.Paste")
			(net "I3C_SPD_DDRABCD_CPU1_BMC_R_SDA")
		)
		(pad "OA11" smd rect
			(at -2.750058 -24.660098 180)
			(size 0.381 1.4478)
			(layers "F.Cu" "F.Mask" "F.Paste")
			(net "I3C_SPD_DDREFGH_CPU1_BMC_R_SCL")
		)
		(pad "OA12" smd rect
			(at -2.750058 -24.059896 180)
			(size 0.381 1.4478)
			(layers "F.Cu" "F.Mask" "F.Paste")
			(net "I3C_SPD_DDREFGH_CPU1_BMC_R_SDA")
		)
		(pad "OA13" smd rect
			(at -2.750058 -23.459948 180)
			(size 0.381 1.4478)
			(layers "F.Cu" "F.Mask" "F.Paste")
			(net "GND")
		)
		(pad "OA14" smd rect
			(at -2.750058 -22.86 180)
			(size 0.381 1.4478)
			(layers "F.Cu" "F.Mask" "F.Paste")
			(net "VIRTUAL_RESEAT")
		)
		(pad "OB1" smd rect
			(at -5.700014 -30.660086 180)
			(size 0.381 1.4478)
			(layers "F.Cu" "F.Mask" "F.Paste")
			(net "P12V_SCM")
		)
		(pad "OB2" smd rect
			(at -5.700014 -30.059884 180)
			(size 0.381 1.4478)
			(layers "F.Cu" "F.Mask" "F.Paste")
			(net "P12V_SCM")
		)
		(pad "OB3" smd rect
			(at -5.700014 -29.459936 180)
			(size 0.381 1.4478)
			(layers "F.Cu" "F.Mask" "F.Paste")
			(net "PRSNT0_N")
		)
		(pad "OB4" smd rect
			(at -5.700014 -28.859988 180)
			(size 0.381 1.4478)
			(layers "F.Cu" "F.Mask" "F.Paste")
			(net "GND")
		)
		(pad "OB5" smd rect
			(at -5.700014 -28.26004 180)
			(size 0.381 1.4478)
			(layers "F.Cu" "F.Mask" "F.Paste")
			(net "UART_BMC_BIC_TX")
		)
		(pad "OB6" smd rect
			(at -5.700014 -27.660092 180)
			(size 0.381 1.4478)
			(layers "F.Cu" "F.Mask" "F.Paste")
			(net "UART_BMC_BIC_BUF_RX")
		)
		(pad "OB7" smd rect
			(at -5.700014 -27.05989 180)
			(size 0.381 1.4478)
			(layers "F.Cu" "F.Mask" "F.Paste")
			(net "GND")
		)
		(pad "OB8" smd rect
			(at -5.700014 -26.459942 180)
			(size 0.381 1.4478)
			(layers "F.Cu" "F.Mask" "F.Paste")
			(net "USB2_7_R_DP")
		)
		(pad "OB9" smd rect
			(at -5.700014 -25.859994 180)
			(size 0.381 1.4478)
			(layers "F.Cu" "F.Mask" "F.Paste")
			(net "USB2_7_R_DN")
		)
		(pad "OB10" smd rect
			(at -5.700014 -25.260046 180)
			(size 0.381 1.4478)
			(layers "F.Cu" "F.Mask" "F.Paste")
			(net "GND")
		)
		(pad "OB11" smd rect
			(at -5.700014 -24.660098 180)
			(size 0.381 1.4478)
			(layers "F.Cu" "F.Mask" "F.Paste")
			(net "RST_SRST_PLD_BMC_N")
		)
		(pad "OB12" smd rect
			(at -5.700014 -24.059896 180)
			(size 0.381 1.4478)
			(layers "F.Cu" "F.Mask" "F.Paste")
			(net "SPI_TPM_CS_N")
		)
		(pad "OB13" smd rect
			(at -5.700014 -23.459948 180)
			(size 0.381 1.4478)
			(layers "F.Cu" "F.Mask" "F.Paste")
			(net "H_CPU_CATERR_LVC2_BMC_N")
		)
		(pad "OB14" smd rect
			(at -5.700014 -22.86 180)
			(size 0.381 1.4478)
			(layers "F.Cu" "F.Mask" "F.Paste")
			(net "FM_SOL_UART_CH_SEL_R")
		)
	)
)
